# T6G (Grand Teton) — schematic parts with pin connectivity, parts 1049–1208 of 8303; source: Cadence DE-HDL packaged netlist (pstxprt.dat, pstxnet.dat, pstchip.dat)

C1048  Q_CAP  0.1UF 10V 10% X7S  pkg C0201  page 312 : 1 = P0V9_CPU0_RT_2D ; 2 = GND
C1049  Q_CAP  10UF 6.3V 20% X6S  pkg C0402  page 312 : 1 = P0V9_CPU0_RT3_2A ; 2 = GND
C1050  Q_CAP  1UF 4V 20% X6S  pkg 0201  page 312 : 1 = P0V9_CPU0_RT3_2A ; 2 = GND
C1051  Q_CAP  0.1UF 10V 10% X7S  pkg C0201  page 312 : 1 = P0V9_CPU0_RT3_2A ; 2 = GND
C1052  Q_CAP  0.1UF 10V 10% X7S  pkg C0201  page 312 : 1 = P0V9_CPU0_RT3_2A ; 2 = GND
C1053  Q_CAP  0.1UF 10V 10% X7S  pkg C0201  page 312 : 1 = P0V9_CPU0_RT3_2A ; 2 = GND
C1054  Q_CAP  4.7UF 6.3V 20% X6S  pkg 0402  page 312 : 1 = P0V9_CPU0_RT3_2A ; 2 = GND
C1055  Q_CAP  0.1UF 10V 10% X7S  pkg C0201  page 312 : 1 = P0V9_CPU0_RT3_2A ; 2 = GND
C1056  Q_CAP  4.7UF 6.3V 20% X6S  pkg 0402  page 312 : 1 = P0V9_CPU0_RT3_2A ; 2 = GND
C1057  Q_CAP  0.1UF 10V 10% X7S  pkg C0201  page 311 : 1 = P1V8_CPU0_RT_1D ; 2 = GND
C1058  Q_CAP  0.1UF 25V 10% X7R  pkg 0402  page 136 : 1 = P3V3_AUX ; 2 = GND
C1059  Q_CAP  0.1UF 25V 10% X7R  pkg 0402  page 136 : 1 = P3V3_AUX ; 2 = GND
C1060  Q_CAP  0.1UF 25V 10% X7R  pkg 0402  page 136 : 1 = P3V3_AUX ; 2 = GND
C1061  Q_CAP  0.1UF 25V 10% X7R  pkg 0402  page 142 : 1 = P3V3_AUX ; 2 = GND
C1062  Q_CAP  0.1UF 25V 10% X7R  pkg 0402  page 142 : 1 = P3V3_AUX ; 2 = GND
C1063  Q_CAP  0.1UF 25V 10% X7R  pkg 0402  page 142 : 1 = P3V3_AUX ; 2 = GND
C1064  Q_CAP  0.1UF 25V 10% X7R  pkg 0402  page 142 : 1 = P3V3_AUX ; 2 = GND
C1065  Q_CAP  0.1UF 25V 10% X7R  pkg 0402  page 142 : 1 = P3V3_AUX ; 2 = GND
C1066  Q_CAP  0.1UF 10V 10% X7S  pkg C0201  page 186 : 1 = P3V3_AUX ; 2 = GND
C1067  Q_CAP  0.1UF 10V 10% X7S  pkg C0201  page 186 : 1 = P3V3_AUX ; 2 = GND
C1068  Q_CAP  0.1UF 10V 10% X7S  pkg C0201  page 186 : 1 = P3V3_AUX ; 2 = GND
C1069  Q_CAP  0.1UF 10V 10% X7S  pkg C0201  page 186 : 1 = P3V3_AUX ; 2 = GND
C1070  Q_CAP  0.1UF 10V 10% X7S  pkg C0201  page 186 : 1 = P3V3_AUX ; 2 = GND
C1071  Q_CAP  0.1UF 10V 10% X7S  pkg C0201  page 186 : 1 = P3V3_AUX ; 2 = GND
C1072  Q_CAP  0.1UF 10V 10% X7S  pkg C0201  page 186 : 1 = P3V3_AUX ; 2 = GND
C1073  Q_CAP  0.1UF 10V 10% X7S  pkg C0201  page 186 : 1 = P3V3_AUX ; 2 = GND
C1074  Q_CAP  0.1UF 25V 10% X7R  pkg 0402  page 258 : 1 = MAX11617_2_VREF ; 2 = GND
C1075  Q_CAP  0.1UF 25V 10% X7R  pkg 0402  page 258 : 1 = P3V3_MAX11617_2_VDD ; 2 = GND
C1076  Q_CAP  10UF 16V 10% X6S  pkg C0805  page 258 : 1 = MAX11617_2_VREF ; 2 = GND
C1077  Q_CAP  10UF 16V 10% X6S  pkg C0805  page 258 : 1 = P3V3_MAX11617_2_VDD ; 2 = GND
C1078  Q_CAP  100PF 50V 5% EMPTY  pkg 0402  page 258 : 1 = P1V2_AUX_ADC_MAM ; 2 = GND
C1079  Q_CAP  100PF 50V 5% EMPTY  pkg 0402  page 258 : 1 = P1V8_CPU0_RT_1D_ADC_MAM ; 2 = GND
C1080  Q_CAP  100PF 50V 5% EMPTY  pkg 0402  page 258 : 1 = PVDD18_S5_P0_ADC_MAM ; 2 = GND
C1081  Q_CAP  100PF 50V 5% EMPTY  pkg 0402  page 258 : 1 = PVDD18_S5_P1_ADC_MAM ; 2 = GND
C1082  Q_CAP  100PF 50V 5% EMPTY  pkg 0402  page 258 : 1 = PVDD_33_S5_ADC_MAM ; 2 = GND
C1083  Q_CAP  100PF 50V 5% EMPTY  pkg 0402  page 258 : 1 = P1V8_CPU1_RT_1D_ADC_MAM ; 2 = GND
C1084  Q_CAP  100PF 50V 5% EMPTY  pkg 0402  page 258 : 1 = P1V8_AUX_ADC_MAM ; 2 = GND
C1085  Q_CAP  100PF 50V 5% EMPTY  pkg 0402  page 258 : 1 = P5V_AUX_ADC_MAM ; 2 = GND
C1086  Q_CAP  0.1UF 25V 10% X7R  pkg 0402  page 258 : 1 = P1V2_AUX_ADC_TIC ; 2 = GND
C1087  Q_CAP  0.1UF 25V 10% X7R  pkg 0402  page 258 : 1 = P1V8_CPU0_RT_1D_ADC_TIC ; 2 = GND
C1088  Q_CAP  0.1UF 25V 10% X7R  pkg 0402  page 258 : 1 = PVDD18_S5_P0_ADC_TIC ; 2 = GND
C1089  Q_CAP  0.1UF 25V 10% X7R  pkg 0402  page 258 : 1 = PVDD_33_S5_ADC_TIC ; 2 = GND
C1090  Q_CAP  0.1UF 25V 10% X7R  pkg 0402  page 258 : 1 = PVDD18_S5_P1_ADC_TIC ; 2 = GND
C1091  Q_CAP  0.1UF 25V 10% X7R  pkg 0402  page 258 : 1 = P1V8_CPU1_RT_1D_ADC_TIC ; 2 = GND
C1092  Q_CAP  0.1UF 25V 10% X7R  pkg 0402  page 258 : 1 = P1V8_AUX_ADC_TIC ; 2 = GND
C1093  Q_CAP  0.1UF 25V 10% X7R  pkg 0402  page 258 : 1 = P5V_AUX_ADC_TIC ; 2 = GND
C1094  Q_CAP  0.1UF 25V 10% X7R  pkg 0402  page 258 : 1 = P3V3_ADC128_2_VCC ; 2 = GND
C1095  Q_CAP  0.1UF 25V 10% X7R  pkg 0402  page 258 : 1 = P3V3_ADC128_2_VCC ; 2 = GND
C1096  Q_CAP  0.1UF 25V 10% X7R  pkg 0402  page 357 : 1 = P3V3_AUX ; 2 = GND
C1097  Q_CAP  0.1UF 25V 10% X7R  pkg 0402  page 357 : 1 = P3V3_AUX ; 2 = GND
C1098  Q_CAP_DIFFBUS  DIFF BUS_0.22UF 6.3V 20% X6S  pkg C0201  page 67 : 1 = P3E_CPU1_P4_TX_C_DP<3> ; 2 = P3E_CPU1_P4_TX_DP<3>
C1099  Q_CAP_DIFFBUS  DIFF BUS_0.22UF 6.3V 20% X6S  pkg C0201  page 67 : 1 = P3E_CPU1_P4_TX_C_DN<3> ; 2 = P3E_CPU1_P4_TX_DN<3>
C1100  Q_CAP_DIFFBUS  DIFF BUS_0.22UF 6.3V 20% X6S  pkg C0201  page 67 : 1 = P3E_CPU1_P4_TX_C_DP<2> ; 2 = P3E_CPU1_P4_TX_DP<2>
C1101  Q_CAP_DIFFBUS  DIFF BUS_0.22UF 6.3V 20% X6S  pkg C0201  page 67 : 1 = P3E_CPU1_P4_TX_C_DN<2> ; 2 = P3E_CPU1_P4_TX_DN<2>
C1102  Q_CAP  0.1UF 25V 10% X7R  pkg 0402  page 77 : 1 = PVDD18_S5_P0 ; 2 = GND
C1103  Q_CAP  0.1UF 25V 10% X7R  pkg 0402  page 77 : 1 = PVDD18_S5_P0 ; 2 = GND
C1104  Q_CAP  0.1UF 25V 10% X7R  pkg 0402  page 77 : 1 = P3V3_AUX ; 2 = GND
C1105  Q_CAP  0.1UF 25V 10% X7R  pkg 0402  page 77 : 1 = P3V3_AUX ; 2 = GND
C1106  Q_CAP  0.1UF 25V 10% X7R  pkg 0402  page 357 : 1 = P3V3_AUX ; 2 = GND
C1107  Q_CAP  0.1UF 25V 10% X7R  pkg 0402  page 357 : 1 = P12V_E1S_0 ; 2 = GND
C1108  Q_CAP  0.1UF 25V 10% X7R  pkg 0402  page 357 : 1 = P12V_OCP_SFF ; 2 = GND
C1109  Q_CAP  0.1UF 25V 10% X7R  pkg 0402  page 357 : 1 = P12V_OCP_V3_2 ; 2 = GND
C1110  Q_CAP  0.1UF 25V 10% X7R  pkg 0402  page 357 : 1 = VSENSE_P12V_INA230_8_INP ; 2 = VSENSE_P12V_INA230_8_INN
C1111  Q_CAP  0.1UF 25V 10% X7R  pkg 0402  page 357 : 1 = VSENSE_P12V_INA230_6_INP ; 2 = VSENSE_P12V_INA230_6_INN
C1112  Q_CAP  0.1UF 25V 10% X7R  pkg 0402  page 357 : 1 = VSENSE_P12V_INA230_7_INP ; 2 = VSENSE_P12V_INA230_7_INN
C1113  Q_CAP  22UF 16V 20% EMPTY  pkg C0805  page 169 : 1 = P12V_AUX_DSC_S1 ; 2 = GND
C1114  Q_CAP  22UF 16V 20% EMPTY  pkg C0805  page 169 : 1 = P3V3_AUX_DSC_S1 ; 2 = GND
C1115  Q_CAP  22UF 16V 20% EMPTY  pkg C0805  page 240 : 1 = PDB_PRSNT_R_N ; 2 = GND
C1126  Q_CAP  0.1UF 16V 10% X7R  pkg C0402  page 83 : 1 = P1V8_AUX ; 2 = GND
C1127  Q_CAP  0.1UF 16V 10% X7R  pkg C0402  page 83 : 1 = P1V8_AUX ; 2 = GND
C1128  Q_CAP  0.1UF 16V 10% X7R  pkg C0402  page 83 : 1 = P1V8_AUX ; 2 = GND
C1129  Q_CAP  0.1UF 16V 10% X7R  pkg C0402  page 83 : 1 = P1V8_AUX ; 2 = GND
C1131  Q_CAP  0.1UF 16V 10% X7R  pkg C0402  page 83 : 1 = P1V8_AUX ; 2 = GND
C1132  Q_CAP  0.1UF 16V 10% X7R  pkg C0402  page 83 : 1 = P1V8_AUX ; 2 = GND
C1133  Q_CAP  0.1UF 16V 10% X7R  pkg C0402  page 83 : 1 = P1V8_AUX ; 2 = GND
C1134  Q_CAP  0.1UF 16V 10% X7R  pkg C0402  page 83 : 1 = P1V8_AUX ; 2 = GND
C1170  Q_CAP  10UF 16V 10% X6S  pkg C0805  page 188 : 1 = P5V_AUX ; 2 = GND
C1171  Q_CAP  0.1UF 16V 10% X7R  pkg C0402  page 83 : 1 = P3V3_AUX ; 2 = GND
C1172  Q_CAP  0.1UF 16V 10% X7R  pkg C0402  page 83 : 1 = P3V3_AUX ; 2 = GND
C1173  Q_CAP  0.1UF 16V 10% X7R  pkg C0402  page 83 : 1 = P3V3_AUX ; 2 = GND
C1174  Q_CAP  0.1UF 16V 10% X7R  pkg C0402  page 83 : 1 = P3V3_AUX ; 2 = GND
C1175  Q_CAP  0.1UF 16V 10% X7R  pkg C0402  page 83 : 1 = P3V3_AUX ; 2 = GND
C1176  Q_CAP  0.1UF 16V 10% X7R  pkg C0402  page 83 : 1 = P3V3_AUX ; 2 = GND
C1209  Q_CAP  100PF 50V 5% NPO  pkg 0402  page 85 : 1 = SCM_SYS_PWROK_R2 ; 2 = GND
C1213  Q_CAP  22UF 16V 20% X6S  pkg C0805  page 131 : 1 = P12V_OCP_SFF_R ; 2 = GND
C1227  Q_CAP  100NF 50V 10% X7R  pkg C0402  page 188 : 1 = P5V ; 2 = GND
C1235  Q_CAP  0.1UF 25V 10% X7R  pkg 0402  page 131 : 1 = P12V_OCP_SFF_R ; 2 = GND
C1236  Q_CAP  0.1UF 25V 10% X7R  pkg 0402  page 131 : 1 = P12V_OCP_SFF_R ; 2 = GND
C1237  Q_CAP  0.1UF 25V 10% X7R  pkg 0402  page 131 : 1 = P3V3_OCP_SFF ; 2 = GND
C1238  Q_CAP  0.1UF 25V 10% X7R  pkg 0402  page 131 : 1 = P3V3_OCP_SFF ; 2 = GND
C1239  Q_CAP  0.1UF 25V 10% X7R  pkg 0402  page 131 : 1 = P3V3_OCP_SFF ; 2 = GND
C1240  Q_CAP  0.1UF 25V 10% X7R  pkg 0402  page 131 : 1 = P3V3_OCP_SFF ; 2 = GND
C1274  Q_CAP  0.1UF 25V 10% X7R  pkg 0402  page 133 : 1 = P3V3_AUX ; 2 = GND
C1275  Q_CAP  0.1UF 25V 10% X7R  pkg 0402  page 133 : 1 = P3V3_AUX ; 2 = GND
C1276  Q_CAP  22UF 16V 20% X6S  pkg C0805  page 145 : 1 = P12V_E1S_0_R ; 2 = GND
C1277  Q_CAP  22UF 16V 20% X6S  pkg C0805  page 145 : 1 = P12V_E1S_0_R ; 2 = GND
C1278  Q_CAP  0.1UF 25V 10% X7R  pkg 0402  page 145 : 1 = P12V_E1S_0_R ; 2 = GND
C1279  Q_CAP  0.1UF 25V 10% X7R  pkg 0402  page 145 : 1 = P12V_E1S_0_R ; 2 = GND
C1282  Q_CAP  0.1UF 25V 10% X7R  pkg 0402  page 145 : 1 = P3V3_E1S_0 ; 2 = GND
C1283  Q_CAP  0.1UF 25V 10% X7R  pkg 0402  page 145 : 1 = P3V3_E1S_0 ; 2 = GND
C1305  Q_CAP  0.1UF 25V 10% X7R  pkg 0402  page 148 : 1 = P3V3_AUX ; 2 = GND
C1323  Q_CAP  0.1UF 25V 10% X7R  pkg 0402  page 148 : 1 = P1V8_AUX ; 2 = GND
C1331  Q_CAP  10UF 16V 10% X6S  pkg C0805  page 188 : 1 = P5V ; 2 = GND
C1332  Q_CAP  100NF 50V 10% X7R  pkg C0402  page 188 : 1 = P3V3_AUX ; 2 = GND
C1333  Q_CAP  10UF 16V 10% X6S  pkg C0805  page 188 : 1 = P3V3_AUX ; 2 = GND
C1336  Q_CAP  0.1UF 25V 10% X7R  pkg 0402  page 159 : 1 = P3V3_AUX ; 2 = GND
C1337  Q_CAP  0.1UF 25V 10% X7R  pkg 0402  page 159 : 1 = P3V3_AUX ; 2 = GND
C1338  Q_CAP  0.1UF 25V 10% X7R  pkg 0402  page 159 : 1 = P3V3_AUX ; 2 = GND
C1339  Q_CAP  0.1UF 25V 10% X7R  pkg 0402  page 159 : 1 = P3V3_AUX ; 2 = GND
C1340  Q_CAP  10UF 16V 10% X6S  pkg C0805  page 188 : 1 = P3V3 ; 2 = GND
C1344  Q_CAP  100PF 50V 5% EMPTY  pkg 0402  page 257 : 1 = P12V_AUX_ADC_MAM ; 2 = GND
C1347  Q_CAP  0.1UF 25V 10% X7R  pkg 0402  page 257 : 1 = MAX11617_VREF ; 2 = GND
C1352  Q_CAP  0.1UF 25V 10% X7R  pkg 0402  page 164 : 1 = PVDD18_S5_P0 ; 2 = GND
C1354  Q_CAP  0.1UF 25V 10% X7R  pkg 0402  page 164 : 1 = P3V3_AUX ; 2 = GND
C1503  Q_CAP  0.1UF 16V 10% X7R  pkg C0402  page 172 : 1 = P3V3_AUX ; 2 = GND
C1504  Q_CAP  0.1UF 16V 10% X7R  pkg C0402  page 172 : 1 = PVDD18_S5_P0 ; 2 = GND
C1505  Q_CAP  0.1UF 16V 10% X7R  pkg C0402  page 172 : 1 = PVDD18_S5_P0 ; 2 = GND
C1506  Q_CAP  0.1UF 16V 10% X7R  pkg C0402  page 172 : 1 = P3V3_AUX ; 2 = GND
C1507  Q_CAP  0.1UF 16V 10% X7R  pkg C0402  page 172 : 1 = PVDD18_S5_P0 ; 2 = GND
C1508  Q_CAP  0.1UF 16V 10% X7R  pkg C0402  page 172 : 1 = PVDD18_S5_P0 ; 2 = GND
C1509  Q_CAP  0.1UF 16V 10% X7R  pkg C0402  page 172 : 1 = PVDD18_S5_P0 ; 2 = GND
C1510  Q_CAP  33PF 50V 5% NPO  pkg 0402  page 172 : 1 = JTAG_TCK ; 2 = GND
C1511  Q_CAP  33PF 50V 5% NPO  pkg 0402  page 172 : 1 = JTAG_TRST_N ; 2 = GND
C1512  Q_CAP  33PF 50V 5% NPO  pkg 0402  page 172 : 1 = JTAG_DBREQ_N ; 2 = GND
C1513  Q_CAP  0.1UF 16V 10% X7R  pkg C0402  page 173 : 1 = PVDD18_S5_P0 ; 2 = GND
C1514  Q_CAP  0.1UF 16V 10% X7R  pkg C0402  page 173 : 1 = PVDD18_S5_P0 ; 2 = GND
C1515  Q_CAP  0.1UF 16V 10% X7R  pkg C0402  page 173 : 1 = PVDD18_S5_P0 ; 2 = GND
C1516  Q_CAP  0.1UF 16V 10% X7R  pkg C0402  page 173 : 1 = PVDD18_S5_P0 ; 2 = GND
C1517  Q_CAP  0.1UF 16V 10% X7R  pkg C0402  page 173 : 1 = PVDD18_S5_P1 ; 2 = GND
C1518  Q_CAP  0.1UF 16V 10% X7R  pkg C0402  page 173 : 1 = PVDD18_S5_P0 ; 2 = GND
C1519  Q_CAP  0.1UF 16V 10% X7R  pkg C0402  page 174 : 1 = PVDD18_S5_P0 ; 2 = GND
C1520  Q_CAP  0.01UF 50V 10% EMPTY  pkg C0402  page 174 : 1 = JTAG_CPU0_TDI ; 2 = GND
C1521  Q_CAP  0.1UF 16V 10% X7R  pkg C0402  page 174 : 1 = PVDD18_S5_P0 ; 2 = GND
C1522  Q_CAP  0.1UF 16V 10% X7R  pkg C0402  page 174 : 1 = PVDD18_S5_P0 ; 2 = GND
C1523  Q_CAP  0.1UF 16V 10% X7R  pkg C0402  page 174 : 1 = PVDD18_S5_P0 ; 2 = GND
C1524  Q_CAP_DIFFBUS  DIFF BUS_0.22UF 6.3V 20% X6S  pkg C0201  page 67 : 1 = P5E_CPU1_P3_TX_C_DN<11> ; 2 = P5E_CPU1_P3_TX_DN<11>
C1525  Q_CAP_DIFFBUS  DIFF BUS_0.22UF 6.3V 20% X6S  pkg C0201  page 67 : 1 = P5E_CPU1_P3_TX_C_DP<11> ; 2 = P5E_CPU1_P3_TX_DP<11>
C1526  Q_CAP_DIFFBUS  DIFF BUS_0.22UF 6.3V 20% X6S  pkg C0201  page 67 : 1 = P5E_CPU1_P3_TX_C_DN<10> ; 2 = P5E_CPU1_P3_TX_DN<10>
C1527  Q_CAP_DIFFBUS  DIFF BUS_0.22UF 6.3V 20% X6S  pkg C0201  page 67 : 1 = P5E_CPU1_P3_TX_C_DP<10> ; 2 = P5E_CPU1_P3_TX_DP<10>
C1528  Q_CAP_DIFFBUS  DIFF BUS_0.22UF 6.3V 20% X6S  pkg C0201  page 67 : 1 = P5E_CPU1_P3_TX_C_DN<9> ; 2 = P5E_CPU1_P3_TX_DN<9>
C1529  Q_CAP_DIFFBUS  DIFF BUS_0.22UF 6.3V 20% X6S  pkg C0201  page 67 : 1 = P5E_CPU1_P3_TX_C_DP<9> ; 2 = P5E_CPU1_P3_TX_DP<9>
C1530  Q_CAP_DIFFBUS  DIFF BUS_0.22UF 6.3V 20% X6S  pkg C0201  page 67 : 1 = P5E_CPU1_P3_TX_C_DN<8> ; 2 = P5E_CPU1_P3_TX_DN<8>
C1531  Q_CAP_DIFFBUS  DIFF BUS_0.22UF 6.3V 20% X6S  pkg C0201  page 67 : 1 = P5E_CPU1_P3_TX_C_DP<8> ; 2 = P5E_CPU1_P3_TX_DP<8>
C1532  Q_CAP_DIFFBUS  DIFF BUS_0.22UF 6.3V 20% X6S  pkg C0201  page 67 : 1 = P5E_CPU1_P3_TX_C_DN<7> ; 2 = P5E_CPU1_P3_TX_DN<7>
C1533  Q_CAP_DIFFBUS  DIFF BUS_0.22UF 6.3V 20% X6S  pkg C0201  page 67 : 1 = P5E_CPU1_P3_TX_C_DP<7> ; 2 = P5E_CPU1_P3_TX_DP<7>
C1534  Q_CAP_DIFFBUS  DIFF BUS_0.22UF 6.3V 20% X6S  pkg C0201  page 67 : 1 = P5E_CPU1_P3_TX_C_DN<6> ; 2 = P5E_CPU1_P3_TX_DN<6>
C1535  Q_CAP_DIFFBUS  DIFF BUS_0.22UF 6.3V 20% X6S  pkg C0201  page 67 : 1 = P5E_CPU1_P3_TX_C_DP<6> ; 2 = P5E_CPU1_P3_TX_DP<6>
C1536  Q_CAP_DIFFBUS  DIFF BUS_0.22UF 6.3V 20% X6S  pkg C0201  page 67 : 1 = P5E_CPU1_P3_TX_C_DN<5> ; 2 = P5E_CPU1_P3_TX_DN<5>
C1537  Q_CAP_DIFFBUS  DIFF BUS_0.22UF 6.3V 20% X6S  pkg C0201  page 67 : 1 = P5E_CPU1_P3_TX_C_DP<5> ; 2 = P5E_CPU1_P3_TX_DP<5>
C1538  Q_CAP_DIFFBUS  DIFF BUS_0.22UF 6.3V 20% X6S  pkg C0201  page 67 : 1 = P5E_CPU1_P3_TX_C_DN<4> ; 2 = P5E_CPU1_P3_TX_DN<4>
C1539  Q_CAP_DIFFBUS  DIFF BUS_0.22UF 6.3V 20% X6S  pkg C0201  page 67 : 1 = P5E_CPU1_P3_TX_C_DP<4> ; 2 = P5E_CPU1_P3_TX_DP<4>
C1540  Q_CAP_DIFFBUS  DIFF BUS_0.22UF 6.3V 20% X6S  pkg C0201  page 67 : 1 = P5E_CPU1_P3_TX_C_DN<3> ; 2 = P5E_CPU1_P3_TX_DN<3>
C1541  Q_CAP_DIFFBUS  DIFF BUS_0.22UF 6.3V 20% X6S  pkg C0201  page 67 : 1 = P5E_CPU1_P3_TX_C_DP<3> ; 2 = P5E_CPU1_P3_TX_DP<3>
C1542  Q_CAP_DIFFBUS  DIFF BUS_0.22UF 6.3V 20% X6S  pkg C0201  page 67 : 1 = P5E_CPU1_P3_TX_C_DN<2> ; 2 = P5E_CPU1_P3_TX_DN<2>
C1543  Q_CAP_DIFFBUS  DIFF BUS_0.22UF 6.3V 20% X6S  pkg C0201  page 67 : 1 = P5E_CPU1_P3_TX_C_DP<2> ; 2 = P5E_CPU1_P3_TX_DP<2>
C1544  Q_CAP_DIFFBUS  DIFF BUS_0.22UF 6.3V 20% X6S  pkg C0201  page 67 : 1 = P5E_CPU1_P3_TX_C_DN<1> ; 2 = P5E_CPU1_P3_TX_DN<1>
C1545  Q_CAP_DIFFBUS  DIFF BUS_0.22UF 6.3V 20% X6S  pkg C0201  page 67 : 1 = P5E_CPU1_P3_TX_C_DP<1> ; 2 = P5E_CPU1_P3_TX_DP<1>
C1546  Q_CAP_DIFFBUS  DIFF BUS_0.22UF 6.3V 20% X6S  pkg C0201  page 67 : 1 = P5E_CPU1_P3_TX_C_DN<0> ; 2 = P5E_CPU1_P3_TX_DN<0>
C1547  Q_CAP_DIFFBUS  DIFF BUS_0.22UF 6.3V 20% X6S  pkg C0201  page 67 : 1 = P5E_CPU1_P3_TX_C_DP<0> ; 2 = P5E_CPU1_P3_TX_DP<0>
C1548  Q_CAP_DIFFBUS  DIFF BUS_0.22UF 6.3V 20% X6S  pkg C0201  page 65 : 1 = P5E_CPU0_G3_TX_C_DN<15> ; 2 = P5E_CPU0_G3_TX_DN<15>
